(kicad_sch (version 20230121) (generator eeschema)

  (paper "A3")

  (title_block
    (title "Scalenode CM4 Baseboard")
    (date "2024-03-26")
    (rev "1.1.3")
    (company "Antmicro")
    (comment 1 "www.antmicro.com")
  )

  (junction (at 240.03 142.24) (diameter 0) (color 0 0 0 0)
  )
  (junction (at 228.6 142.24) (diameter 0) (color 0 0 0 0)
  )
  (junction (at 215.9 142.24) (diameter 0) (color 0 0 0 0)
  )
  (junction (at 166.37 142.24) (diameter 0) (color 0 0 0 0)
  )
  (junction (at 250.19 142.24) (diameter 0) (color 0 0 0 0)
  )
  (junction (at 228.6 152.4) (diameter 0) (color 0 0 0 0)
  )

  (wire (pts (xy 166.37 153.67) (xy 166.37 161.29))
    (stroke (width 0) (type default))
  )
  (wire (pts (xy 228.6 152.4) (xy 228.6 154.94))
    (stroke (width 0) (type default))
  )
  (wire (pts (xy 256.54 142.24) (xy 250.19 142.24))
    (stroke (width 0) (type default))
  )
  (wire (pts (xy 228.6 149.86) (xy 228.6 152.4))
    (stroke (width 0) (type default))
  )
  (wire (pts (xy 228.6 142.24) (xy 240.03 142.24))
    (stroke (width 0) (type default))
  )
  (wire (pts (xy 250.19 153.67) (xy 250.19 161.29))
    (stroke (width 0) (type default))
  )
  (wire (pts (xy 215.9 147.32) (xy 215.9 142.24))
    (stroke (width 0) (type default))
  )
  (wire (pts (xy 240.03 142.24) (xy 240.03 148.59))
    (stroke (width 0) (type default))
  )
  (wire (pts (xy 250.19 142.24) (xy 250.19 148.59))
    (stroke (width 0) (type default))
  )
  (wire (pts (xy 228.6 160.02) (xy 228.6 161.29))
    (stroke (width 0) (type default))
  )
  (wire (pts (xy 240.03 140.97) (xy 240.03 142.24))
    (stroke (width 0) (type default))
  )
  (wire (pts (xy 166.37 142.24) (xy 185.42 142.24))
    (stroke (width 0) (type default))
  )
  (wire (pts (xy 240.03 153.67) (xy 240.03 161.29))
    (stroke (width 0) (type default))
  )
  (wire (pts (xy 215.9 142.24) (xy 205.74 142.24))
    (stroke (width 0) (type default))
  )
  (wire (pts (xy 184.15 152.4) (xy 185.42 152.4))
    (stroke (width 0) (type default))
  )
  (wire (pts (xy 180.34 147.32) (xy 185.42 147.32))
    (stroke (width 0) (type default))
  )
  (wire (pts (xy 240.03 142.24) (xy 250.19 142.24))
    (stroke (width 0) (type default))
  )
  (wire (pts (xy 156.21 142.24) (xy 166.37 142.24))
    (stroke (width 0) (type default))
  )
  (wire (pts (xy 156.21 139.7) (xy 156.21 142.24))
    (stroke (width 0) (type default))
  )
  (wire (pts (xy 166.37 142.24) (xy 166.37 148.59))
    (stroke (width 0) (type default))
  )
  (wire (pts (xy 215.9 142.24) (xy 218.44 142.24))
    (stroke (width 0) (type default))
  )
  (wire (pts (xy 205.74 147.32) (xy 208.28 147.32))
    (stroke (width 0) (type default))
  )
  (wire (pts (xy 213.36 147.32) (xy 215.9 147.32))
    (stroke (width 0) (type default))
  )
  (wire (pts (xy 228.6 142.24) (xy 228.6 144.78))
    (stroke (width 0) (type default))
  )
  (wire (pts (xy 184.15 161.29) (xy 184.15 152.4))
    (stroke (width 0) (type default))
  )
  (wire (pts (xy 256.54 139.7) (xy 256.54 142.24))
    (stroke (width 0) (type default))
  )
  (wire (pts (xy 205.74 152.4) (xy 228.6 152.4))
    (stroke (width 0) (type default))
  )

  (text "SSD 3V3 DC/DC converter" (at 180.467 122.047 0)
    (effects (font (size 2.54 2.54) (thickness 0.508) bold) (justify left bottom))
  )

  (global_label "3V3_SSD" (shape input) (at 256.54 139.7 90) (fields_autoplaced)
    (effects (font (size 1.27 1.27)) (justify left))
    (property "Intersheetrefs" "${INTERSHEET_REFS}" (at 256.4606 129.2115 90)
      (effects (font (size 1.27 1.27)) (justify left) hide)
    )
  )
  (global_label "VCC5V0" (shape input) (at 156.21 139.7 90) (fields_autoplaced)
    (effects (font (size 1.27 1.27)) (justify left))
    (property "Intersheetrefs" "${INTERSHEET_REFS}" (at 156.1306 130.2396 90)
      (effects (font (size 1.27 1.27)) (justify left) hide)
    )
  )

  (symbol (lib_id "scalenode-cm4-baseboard:C_22u_0805_10V") (at 166.37 153.67 90) (unit 1)
    (in_bom yes) (on_board yes) (dnp no)
    (property "Reference" "C16" (at 168.91 151.13 90)
      (effects (font (size 1.27 1.27) (thickness 0.15)) (justify right top))
    )
    (property "Value" "C_22u_0805_10V" (at 176.53 133.35 0)
      (effects (font (size 1.27 1.27) (thickness 0.15)) (justify left bottom) hide)
    )
    (property "Footprint" "scalenode-cm4-baseboard-footprints:C_0805_2012Metric" (at 179.07 133.35 0)
      (effects (font (size 1.27 1.27) (thickness 0.15)) (justify left bottom) hide)
    )
    (property "Datasheet" "https://spicat.kyocera-avx.com/product/mlcc/chartview/0805ZD226MAT2A/" (at 181.61 133.35 0)
      (effects (font (size 1.27 1.27) (thickness 0.15)) (justify left bottom) hide)
    )
    (property "Manufacturer" "AVX" (at 186.69 133.35 0)
      (effects (font (size 1.27 1.27) (thickness 0.15)) (justify left bottom) hide)
    )
    (property "MPN" "0805ZD226MAT2A" (at 184.15 133.35 0)
      (effects (font (size 1.27 1.27) (thickness 0.15)) (justify left bottom) hide)
    )
    (property "Val" "22u" (at 168.91 151.13 90)
      (effects (font (size 1.27 1.27) (thickness 0.15)) (justify right bottom))
    )
    (property "License" "Apache-2.0" (at 189.23 133.35 0)
      (effects (font (size 1.27 1.27) (thickness 0.15)) (justify left bottom) hide)
    )
    (property "Author" "Antmicro" (at 191.77 133.35 0)
      (effects (font (size 1.27 1.27) (thickness 0.15)) (justify left bottom) hide)
    )
    (property "Voltage" "" (at 194.31 133.35 0)
      (effects (font (size 1.27 1.27)) (justify left bottom) hide)
    )
    (property "Dielectric" "" (at 196.85 133.35 0)
      (effects (font (size 1.27 1.27)) (justify left bottom) hide)
    )
    (pin "1")
    (pin "2")
    (instances
      (project "scalenode-cm4-baseboard"
        (path ""
          (reference "C16") (unit 1)
        )
      )
    )
  )

  (symbol (lib_id "scalenode-cm4-baseboard:GND") (at 240.03 161.29 0) (unit 1)
    (in_bom yes) (on_board yes) (dnp no) (fields_autoplaced)
    (property "Reference" "#PWR0112" (at 248.92 163.83 0)
      (effects (font (size 1.27 1.27) (thickness 0.15)) (justify left bottom) hide)
    )
    (property "Value" "GND" (at 238.0198 166.37 0)
      (effects (font (size 1.27 1.27) (thickness 0.15)) (justify left bottom))
    )
    (property "Footprint" "" (at 248.92 168.91 0)
      (effects (font (size 1.27 1.27) (thickness 0.15)) (justify left bottom) hide)
    )
    (property "Datasheet" "" (at 248.92 173.99 0)
      (effects (font (size 1.27 1.27) (thickness 0.15)) (justify left bottom) hide)
    )
    (property "Author" "Antmicro" (at 248.92 168.91 0)
      (effects (font (size 1.27 1.27) (thickness 0.15)) (justify left bottom) hide)
    )
    (property "License" "Apache-2.0" (at 248.92 171.45 0)
      (effects (font (size 1.27 1.27) (thickness 0.15)) (justify left bottom) hide)
    )
    (pin "1")
    (instances
      (project "scalenode-cm4-baseboard"
        (path ""
          (reference "#PWR0112") (unit 1)
        )
      )
    )
  )

  (symbol (lib_id "scalenode-cm4-baseboard:GND") (at 184.15 161.29 0) (unit 1)
    (in_bom yes) (on_board yes) (dnp no) (fields_autoplaced)
    (property "Reference" "#PWR0114" (at 193.04 163.83 0)
      (effects (font (size 1.27 1.27) (thickness 0.15)) (justify left bottom) hide)
    )
    (property "Value" "GND" (at 182.1398 166.37 0)
      (effects (font (size 1.27 1.27) (thickness 0.15)) (justify left bottom))
    )
    (property "Footprint" "" (at 193.04 168.91 0)
      (effects (font (size 1.27 1.27) (thickness 0.15)) (justify left bottom) hide)
    )
    (property "Datasheet" "" (at 193.04 173.99 0)
      (effects (font (size 1.27 1.27) (thickness 0.15)) (justify left bottom) hide)
    )
    (property "Author" "Antmicro" (at 193.04 168.91 0)
      (effects (font (size 1.27 1.27) (thickness 0.15)) (justify left bottom) hide)
    )
    (property "License" "Apache-2.0" (at 193.04 171.45 0)
      (effects (font (size 1.27 1.27) (thickness 0.15)) (justify left bottom) hide)
    )
    (pin "1")
    (instances
      (project "scalenode-cm4-baseboard"
        (path ""
          (reference "#PWR0114") (unit 1)
        )
      )
    )
  )

  (symbol (lib_id "scalenode-cm4-baseboard:GND") (at 166.37 161.29 0) (unit 1)
    (in_bom yes) (on_board yes) (dnp no) (fields_autoplaced)
    (property "Reference" "#PWR0115" (at 175.26 163.83 0)
      (effects (font (size 1.27 1.27) (thickness 0.15)) (justify left bottom) hide)
    )
    (property "Value" "GND" (at 164.3598 166.37 0)
      (effects (font (size 1.27 1.27) (thickness 0.15)) (justify left bottom))
    )
    (property "Footprint" "" (at 175.26 168.91 0)
      (effects (font (size 1.27 1.27) (thickness 0.15)) (justify left bottom) hide)
    )
    (property "Datasheet" "" (at 175.26 173.99 0)
      (effects (font (size 1.27 1.27) (thickness 0.15)) (justify left bottom) hide)
    )
    (property "Author" "Antmicro" (at 175.26 168.91 0)
      (effects (font (size 1.27 1.27) (thickness 0.15)) (justify left bottom) hide)
    )
    (property "License" "Apache-2.0" (at 175.26 171.45 0)
      (effects (font (size 1.27 1.27) (thickness 0.15)) (justify left bottom) hide)
    )
    (pin "1")
    (instances
      (project "scalenode-cm4-baseboard"
        (path ""
          (reference "#PWR0115") (unit 1)
        )
      )
    )
  )

  (symbol (lib_id "scalenode-cm4-baseboard:AP62301_TSOT") (at 185.42 142.24 0) (unit 1)
    (in_bom yes) (on_board yes) (dnp no) (fields_autoplaced)
    (property "Reference" "U2" (at 188.52 134.62 0)
      (effects (font (size 1.27 1.27) (thickness 0.15)) (justify left bottom))
    )
    (property "Value" "AP62301_TSOT" (at 220.98 149.86 0)
      (effects (font (size 1.27 1.27) (thickness 0.15)) (justify left bottom) hide)
    )
    (property "Footprint" "scalenode-cm4-baseboard-footprints:TSOT23-6" (at 220.98 152.4 0)
      (effects (font (size 1.27 1.27) (thickness 0.15)) (justify left bottom) hide)
    )
    (property "Datasheet" "https://www.diodes.com/assets/Datasheets/AP62300_AP62301_AP62300T.pdf" (at 220.98 154.94 0)
      (effects (font (size 1.27 1.27) (thickness 0.15)) (justify left bottom) hide)
    )
    (property "MPN" "AP62301WU-7" (at 188.52 137.16 0)
      (effects (font (size 1.27 1.27) (thickness 0.15)) (justify left bottom))
    )
    (property "Manufacturer" "Diodes Incorporated" (at 220.98 157.48 0)
      (effects (font (size 1.27 1.27) (thickness 0.15)) (justify left bottom) hide)
    )
    (property "Author" "Antmicro" (at 220.98 160.02 0)
      (effects (font (size 1.27 1.27) (thickness 0.15)) (justify left bottom) hide)
    )
    (property "License" "Apache-2.0" (at 220.98 162.56 0)
      (effects (font (size 1.27 1.27) (thickness 0.15)) (justify left bottom) hide)
    )
    (pin "1")
    (pin "2")
    (pin "3")
    (pin "4")
    (pin "5")
    (pin "6")
    (instances
      (project "scalenode-cm4-baseboard"
        (path ""
          (reference "U2") (unit 1)
        )
      )
    )
  )

  (symbol (lib_id "scalenode-cm4-baseboard:C_22u_0805_10V") (at 240.03 153.67 90) (unit 1)
    (in_bom yes) (on_board yes) (dnp no)
    (property "Reference" "C18" (at 242.57 151.13 90)
      (effects (font (size 1.27 1.27) (thickness 0.15)) (justify right top))
    )
    (property "Value" "C_22u_0805_10V" (at 250.19 133.35 0)
      (effects (font (size 1.27 1.27) (thickness 0.15)) (justify left bottom) hide)
    )
    (property "Footprint" "scalenode-cm4-baseboard-footprints:C_0805_2012Metric" (at 252.73 133.35 0)
      (effects (font (size 1.27 1.27) (thickness 0.15)) (justify left bottom) hide)
    )
    (property "Datasheet" "https://spicat.kyocera-avx.com/product/mlcc/chartview/0805ZD226MAT2A/" (at 255.27 133.35 0)
      (effects (font (size 1.27 1.27) (thickness 0.15)) (justify left bottom) hide)
    )
    (property "Manufacturer" "AVX" (at 260.35 133.35 0)
      (effects (font (size 1.27 1.27) (thickness 0.15)) (justify left bottom) hide)
    )
    (property "MPN" "0805ZD226MAT2A" (at 257.81 133.35 0)
      (effects (font (size 1.27 1.27) (thickness 0.15)) (justify left bottom) hide)
    )
    (property "Val" "22u" (at 242.57 151.13 90)
      (effects (font (size 1.27 1.27) (thickness 0.15)) (justify right bottom))
    )
    (property "License" "Apache-2.0" (at 262.89 133.35 0)
      (effects (font (size 1.27 1.27) (thickness 0.15)) (justify left bottom) hide)
    )
    (property "Author" "Antmicro" (at 265.43 133.35 0)
      (effects (font (size 1.27 1.27) (thickness 0.15)) (justify left bottom) hide)
    )
    (property "Voltage" "" (at 267.97 133.35 0)
      (effects (font (size 1.27 1.27)) (justify left bottom) hide)
    )
    (property "Dielectric" "" (at 270.51 133.35 0)
      (effects (font (size 1.27 1.27)) (justify left bottom) hide)
    )
    (pin "1")
    (pin "2")
    (instances
      (project "scalenode-cm4-baseboard"
        (path ""
          (reference "C18") (unit 1)
        )
      )
    )
  )

  (symbol (lib_id "scalenode-cm4-baseboard:TP_1mm_SMD") (at 240.03 140.97 90) (unit 1)
    (in_bom yes) (on_board yes) (dnp no) (fields_autoplaced)
    (property "Reference" "TP7" (at 245.11 137.7949 90)
      (effects (font (size 1.27 1.27) (thickness 0.15)) (justify left bottom))
    )
    (property "Value" "TP_1mm_SMD" (at 247.65 125.73 0)
      (effects (font (size 1.27 1.27) (thickness 0.15)) (justify left bottom) hide)
    )
    (property "Footprint" "scalenode-cm4-baseboard-footprints:TP_SMD_1mm" (at 250.19 125.73 0)
      (effects (font (size 1.27 1.27) (thickness 0.15)) (justify left bottom) hide)
    )
    (property "Datasheet" "" (at 252.73 125.73 0)
      (effects (font (size 1.27 1.27) (thickness 0.15)) (justify left bottom) hide)
    )
    (property "Author" "Antmicro" (at 255.27 125.73 0)
      (effects (font (size 1.27 1.27) (thickness 0.15)) (justify left bottom) hide)
    )
    (property "License" "Apache-2.0" (at 257.81 125.73 0)
      (effects (font (size 1.27 1.27) (thickness 0.15)) (justify left bottom) hide)
    )
    (property "MPN" "" (at 240.03 140.97 0)
      (effects (font (size 1.27 1.27)) hide)
    )
    (property "Manufacturer" "" (at 240.03 140.97 0)
      (effects (font (size 1.27 1.27)) hide)
    )
    (pin "1")
    (instances
      (project "scalenode-cm4-baseboard"
        (path ""
          (reference "TP7") (unit 1)
        )
      )
    )
  )

  (symbol (lib_id "scalenode-cm4-baseboard:PWR_FLAG") (at 166.37 142.24 0) (unit 1)
    (in_bom yes) (on_board yes) (dnp no) (fields_autoplaced)
    (property "Reference" "#FLG0101" (at 166.37 140.335 0)
      (effects (font (size 1.27 1.27)) hide)
    )
    (property "Value" "PWR_FLAG" (at 166.37 137.16 0)
      (effects (font (size 1.27 1.27)))
    )
    (property "Footprint" "" (at 166.37 142.24 0)
      (effects (font (size 1.27 1.27)) hide)
    )
    (property "Datasheet" "" (at 166.37 142.24 0)
      (effects (font (size 1.27 1.27)) hide)
    )
    (pin "1")
    (instances
      (project "scalenode-cm4-baseboard"
        (path ""
          (reference "#FLG0101") (unit 1)
        )
      )
    )
  )

  (symbol (lib_id "scalenode-cm4-baseboard:R_33k2_0402") (at 228.6 149.86 90) (unit 1)
    (in_bom yes) (on_board yes) (dnp no)
    (property "Reference" "R18" (at 229.87 147.32 90)
      (effects (font (size 1.27 1.27) (thickness 0.15)) (justify right top))
    )
    (property "Value" "R_33k2_0402" (at 241.3 129.54 0)
      (effects (font (size 1.27 1.27) (thickness 0.15)) (justify left bottom) hide)
    )
    (property "Footprint" "scalenode-cm4-baseboard-footprints:R_0402_1005Metric" (at 243.84 129.54 0)
      (effects (font (size 1.27 1.27) (thickness 0.15)) (justify left bottom) hide)
    )
    (property "Datasheet" "https://www.bourns.com/docs/product-datasheets/cr.pdf" (at 246.38 129.54 0)
      (effects (font (size 1.27 1.27) (thickness 0.15)) (justify left bottom) hide)
    )
    (property "Manufacturer" "Bourns" (at 251.46 129.54 0)
      (effects (font (size 1.27 1.27) (thickness 0.15)) (justify left bottom) hide)
    )
    (property "MPN" "CR0402-FX-3322GLF" (at 248.92 129.54 0)
      (effects (font (size 1.27 1.27) (thickness 0.15)) (justify left bottom) hide)
    )
    (property "Val" "33k2" (at 229.87 147.32 90)
      (effects (font (size 1.27 1.27) (thickness 0.15)) (justify right bottom))
    )
    (property "License" "Apache-2.0" (at 254 129.54 0)
      (effects (font (size 1.27 1.27) (thickness 0.15)) (justify left bottom) hide)
    )
    (property "Author" "Antmicro" (at 256.54 129.54 0)
      (effects (font (size 1.27 1.27) (thickness 0.15)) (justify left bottom) hide)
    )
    (property "Tolerance" "1%" (at 238.76 129.54 0)
      (effects (font (size 1.27 1.27)) (justify left bottom) hide)
    )
    (pin "1")
    (pin "2")
    (instances
      (project "scalenode-cm4-baseboard"
        (path ""
          (reference "R18") (unit 1)
        )
      )
    )
  )

  (symbol (lib_id "scalenode-cm4-baseboard:R_10k_0402") (at 228.6 160.02 90) (unit 1)
    (in_bom yes) (on_board yes) (dnp no)
    (property "Reference" "R19" (at 229.87 157.48 90)
      (effects (font (size 1.27 1.27) (thickness 0.15)) (justify right top))
    )
    (property "Value" "R_10k_0402" (at 241.3 139.7 0)
      (effects (font (size 1.27 1.27) (thickness 0.15)) (justify left bottom) hide)
    )
    (property "Footprint" "scalenode-cm4-baseboard-footprints:R_0402_1005Metric" (at 243.84 139.7 0)
      (effects (font (size 1.27 1.27) (thickness 0.15)) (justify left bottom) hide)
    )
    (property "Datasheet" "https://www.bourns.com/docs/product-datasheets/cr.pdf" (at 246.38 139.7 0)
      (effects (font (size 1.27 1.27) (thickness 0.15)) (justify left bottom) hide)
    )
    (property "Manufacturer" "Bourns" (at 251.46 139.7 0)
      (effects (font (size 1.27 1.27) (thickness 0.15)) (justify left bottom) hide)
    )
    (property "MPN" "CR0402-FX-1002GLF" (at 248.92 139.7 0)
      (effects (font (size 1.27 1.27) (thickness 0.15)) (justify left bottom) hide)
    )
    (property "Val" "10k" (at 229.87 157.48 90)
      (effects (font (size 1.27 1.27) (thickness 0.15)) (justify right bottom))
    )
    (property "License" "Apache-2.0" (at 254 139.7 0)
      (effects (font (size 1.27 1.27) (thickness 0.15)) (justify left bottom) hide)
    )
    (property "Author" "Antmicro" (at 256.54 139.7 0)
      (effects (font (size 1.27 1.27) (thickness 0.15)) (justify left bottom) hide)
    )
    (property "Tolerance" "1%" (at 238.76 139.7 0)
      (effects (font (size 1.27 1.27)) (justify left bottom) hide)
    )
    (pin "1")
    (pin "2")
    (instances
      (project "scalenode-cm4-baseboard"
        (path ""
          (reference "R19") (unit 1)
        )
      )
    )
  )

  (symbol (lib_id "scalenode-cm4-baseboard:GND") (at 228.6 161.29 0) (unit 1)
    (in_bom yes) (on_board yes) (dnp no) (fields_autoplaced)
    (property "Reference" "#PWR0109" (at 237.49 163.83 0)
      (effects (font (size 1.27 1.27) (thickness 0.15)) (justify left bottom) hide)
    )
    (property "Value" "GND" (at 226.5898 166.37 0)
      (effects (font (size 1.27 1.27) (thickness 0.15)) (justify left bottom))
    )
    (property "Footprint" "" (at 237.49 168.91 0)
      (effects (font (size 1.27 1.27) (thickness 0.15)) (justify left bottom) hide)
    )
    (property "Datasheet" "" (at 237.49 173.99 0)
      (effects (font (size 1.27 1.27) (thickness 0.15)) (justify left bottom) hide)
    )
    (property "Author" "Antmicro" (at 237.49 168.91 0)
      (effects (font (size 1.27 1.27) (thickness 0.15)) (justify left bottom) hide)
    )
    (property "License" "Apache-2.0" (at 237.49 171.45 0)
      (effects (font (size 1.27 1.27) (thickness 0.15)) (justify left bottom) hide)
    )
    (pin "1")
    (instances
      (project "scalenode-cm4-baseboard"
        (path ""
          (reference "#PWR0109") (unit 1)
        )
      )
    )
  )

  (symbol (lib_id "scalenode-cm4-baseboard:C_22u_0805_10V") (at 250.19 153.67 90) (unit 1)
    (in_bom yes) (on_board yes) (dnp no)
    (property "Reference" "C19" (at 252.73 151.13 90)
      (effects (font (size 1.27 1.27) (thickness 0.15)) (justify right top))
    )
    (property "Value" "C_22u_0805_10V" (at 260.35 133.35 0)
      (effects (font (size 1.27 1.27) (thickness 0.15)) (justify left bottom) hide)
    )
    (property "Footprint" "scalenode-cm4-baseboard-footprints:C_0805_2012Metric" (at 262.89 133.35 0)
      (effects (font (size 1.27 1.27) (thickness 0.15)) (justify left bottom) hide)
    )
    (property "Datasheet" "https://spicat.kyocera-avx.com/product/mlcc/chartview/0805ZD226MAT2A/" (at 265.43 133.35 0)
      (effects (font (size 1.27 1.27) (thickness 0.15)) (justify left bottom) hide)
    )
    (property "Manufacturer" "AVX" (at 270.51 133.35 0)
      (effects (font (size 1.27 1.27) (thickness 0.15)) (justify left bottom) hide)
    )
    (property "MPN" "0805ZD226MAT2A" (at 267.97 133.35 0)
      (effects (font (size 1.27 1.27) (thickness 0.15)) (justify left bottom) hide)
    )
    (property "Val" "22u" (at 252.73 151.13 90)
      (effects (font (size 1.27 1.27) (thickness 0.15)) (justify right bottom))
    )
    (property "License" "Apache-2.0" (at 273.05 133.35 0)
      (effects (font (size 1.27 1.27) (thickness 0.15)) (justify left bottom) hide)
    )
    (property "Author" "Antmicro" (at 275.59 133.35 0)
      (effects (font (size 1.27 1.27) (thickness 0.15)) (justify left bottom) hide)
    )
    (property "Voltage" "" (at 278.13 133.35 0)
      (effects (font (size 1.27 1.27)) (justify left bottom) hide)
    )
    (property "Dielectric" "" (at 280.67 133.35 0)
      (effects (font (size 1.27 1.27)) (justify left bottom) hide)
    )
    (pin "1")
    (pin "2")
    (instances
      (project "scalenode-cm4-baseboard"
        (path ""
          (reference "C19") (unit 1)
        )
      )
    )
  )

  (symbol (lib_id "scalenode-cm4-baseboard:TP_1mm_SMD") (at 180.34 147.32 180) (unit 1)
    (in_bom yes) (on_board yes) (dnp no)
    (property "Reference" "TP2" (at 179.07 148.59 0)
      (effects (font (size 1.27 1.27) (thickness 0.15)) (justify left bottom))
    )
    (property "Value" "TP_1mm_SMD" (at 165.1 139.7 0)
      (effects (font (size 1.27 1.27) (thickness 0.15)) (justify left bottom) hide)
    )
    (property "Footprint" "scalenode-cm4-baseboard-footprints:TP_SMD_1mm" (at 165.1 137.16 0)
      (effects (font (size 1.27 1.27) (thickness 0.15)) (justify left bottom) hide)
    )
    (property "Datasheet" "" (at 165.1 134.62 0)
      (effects (font (size 1.27 1.27) (thickness 0.15)) (justify left bottom) hide)
    )
    (property "Author" "Antmicro" (at 165.1 132.08 0)
      (effects (font (size 1.27 1.27) (thickness 0.15)) (justify left bottom) hide)
    )
    (property "License" "Apache-2.0" (at 165.1 129.54 0)
      (effects (font (size 1.27 1.27) (thickness 0.15)) (justify left bottom) hide)
    )
    (property "MPN" "" (at 180.34 147.32 0)
      (effects (font (size 1.27 1.27)) hide)
    )
    (property "Manufacturer" "" (at 180.34 147.32 0)
      (effects (font (size 1.27 1.27)) hide)
    )
    (pin "1")
    (instances
      (project "scalenode-cm4-baseboard"
        (path ""
          (reference "TP2") (unit 1)
        )
      )
    )
  )

  (symbol (lib_id "scalenode-cm4-baseboard:C_100n_0402") (at 213.36 147.32 180) (unit 1)
    (in_bom yes) (on_board yes) (dnp no)
    (property "Reference" "C17" (at 210.82 144.78 0)
      (effects (font (size 1.27 1.27) (thickness 0.15)))
    )
    (property "Value" "C_100n_0402" (at 193.04 137.16 0)
      (effects (font (size 1.27 1.27) (thickness 0.15)) (justify left bottom) hide)
    )
    (property "Footprint" "scalenode-cm4-baseboard-footprints:C_0402_1005Metric" (at 193.04 134.62 0)
      (effects (font (size 1.27 1.27) (thickness 0.15)) (justify left bottom) hide)
    )
    (property "Datasheet" "https://www.murata.com/products/productdetail?partno=GRM155R61H104KE14%23" (at 193.04 132.08 0)
      (effects (font (size 1.27 1.27) (thickness 0.15)) (justify left bottom) hide)
    )
    (property "Manufacturer" "Murata" (at 193.04 127 0)
      (effects (font (size 1.27 1.27) (thickness 0.15)) (justify left bottom) hide)
    )
    (property "MPN" "GRM155R61H104KE14D" (at 193.04 129.54 0)
      (effects (font (size 1.27 1.27) (thickness 0.15)) (justify left bottom) hide)
    )
    (property "Val" "100n" (at 210.82 149.86 0)
      (effects (font (size 1.27 1.27) (thickness 0.15)))
    )
    (property "License" "Apache-2.0" (at 193.04 124.46 0)
      (effects (font (size 1.27 1.27) (thickness 0.15)) (justify left bottom) hide)
    )
    (property "Author" "Antmicro" (at 193.04 121.92 0)
      (effects (font (size 1.27 1.27) (thickness 0.15)) (justify left bottom) hide)
    )
    (property "Voltage" "50V" (at 193.04 119.38 0)
      (effects (font (size 1.27 1.27)) (justify left bottom) hide)
    )
    (property "Dielectric" "X5R" (at 193.04 116.84 0)
      (effects (font (size 1.27 1.27)) (justify left bottom) hide)
    )
    (pin "1")
    (pin "2")
    (instances
      (project "scalenode-cm4-baseboard"
        (path ""
          (reference "C17") (unit 1)
        )
      )
    )
  )

  (symbol (lib_id "scalenode-cm4-baseboard:GND") (at 250.19 161.29 0) (unit 1)
    (in_bom yes) (on_board yes) (dnp no) (fields_autoplaced)
    (property "Reference" "#PWR0106" (at 259.08 163.83 0)
      (effects (font (size 1.27 1.27) (thickness 0.15)) (justify left bottom) hide)
    )
    (property "Value" "GND" (at 248.1798 166.37 0)
      (effects (font (size 1.27 1.27) (thickness 0.15)) (justify left bottom))
    )
    (property "Footprint" "" (at 259.08 168.91 0)
      (effects (font (size 1.27 1.27) (thickness 0.15)) (justify left bottom) hide)
    )
    (property "Datasheet" "" (at 259.08 173.99 0)
      (effects (font (size 1.27 1.27) (thickness 0.15)) (justify left bottom) hide)
    )
    (property "Author" "Antmicro" (at 259.08 168.91 0)
      (effects (font (size 1.27 1.27) (thickness 0.15)) (justify left bottom) hide)
    )
    (property "License" "Apache-2.0" (at 259.08 171.45 0)
      (effects (font (size 1.27 1.27) (thickness 0.15)) (justify left bottom) hide)
    )
    (pin "1")
    (instances
      (project "scalenode-cm4-baseboard"
        (path ""
          (reference "#PWR0106") (unit 1)
        )
      )
    )
  )

  (symbol (lib_id "scalenode-cm4-baseboard:L_1u_5.5A_Bourns-SRP3212A") (at 218.44 142.24 0) (unit 1)
    (in_bom yes) (on_board yes) (dnp no)
    (property "Reference" "L1" (at 222.25 137.16 0)
      (effects (font (size 1.27 1.27) (thickness 0.15)) (justify left bottom))
    )
    (property "Value" "L_1u_5.5A_Bourns-SRP3212A" (at 214.63 139.7 0)
      (effects (font (size 1.27 1.27) (thickness 0.15)) (justify left bottom))
    )
    (property "Footprint" "scalenode-cm4-baseboard-footprints:L_Bourns-SRP3212A" (at 229.87 154.94 0)
      (effects (font (size 1.27 1.27) (thickness 0.15)) (justify left bottom) hide)
    )
    (property "Datasheet" "https://www.mouser.com/datasheet/2/54/SRP3212A-3011944.pdf" (at 229.87 157.48 0)
      (effects (font (size 1.27 1.27) (thickness 0.15)) (justify left bottom) hide)
    )
    (property "Manufacturer" "Bourns" (at 229.87 160.02 0)
      (effects (font (size 1.27 1.27) (thickness 0.15)) (justify left bottom) hide)
    )
    (property "MPN" "SRP3212A-1R0M" (at 229.87 162.56 0)
      (effects (font (size 1.27 1.27) (thickness 0.15)) (justify left bottom) hide)
    )
    (property "MaxCur" "5.5A" (at 229.87 165.1 0)
      (effects (font (size 1.27 1.27) (thickness 0.15)) (justify left bottom) hide)
    )
    (property "Size" "3.2x2.5" (at 229.87 167.64 0)
      (effects (font (size 1.27 1.27) (thickness 0.15)) (justify left bottom) hide)
    )
    (property "Val" "1u/5.5A" (at 219.71 144.78 0)
      (effects (font (size 1.27 1.27) (thickness 0.15)) (justify left bottom))
    )
    (property "Author" "Antmicro" (at 229.87 170.18 0)
      (effects (font (size 1.27 1.27) (thickness 0.15)) (justify left bottom) hide)
    )
    (property "License" "Apache-2.0" (at 229.87 172.72 0)
      (effects (font (size 1.27 1.27) (thickness 0.15)) (justify left bottom) hide)
    )
    (pin "1")
    (pin "2")
    (instances
      (project "scalenode-cm4-baseboard"
        (path ""
          (reference "L1") (unit 1)
        )
      )
    )
  )
)
